(kicad_pcb
	(version 20260206)
	(generator "pcbnew")
	(generator_version "10.0")
	(general
		(thickness 1.6)
		(legacy_teardrops no)
	)
	(paper "A4")
	(title_block
		(title "Bryce Canyon_IOM_M2_16342-2_OCP.brd")
		(comment 1 "Bryce Canyon / footprints 391-397 of 1146")
	)
	(layers
		(0 "F.Cu" signal "TOP")
		(4 "In1.Cu" signal "L2GND")
		(6 "In2.Cu" signal "L3")
		(8 "In3.Cu" signal "L4VCC")
		(10 "In4.Cu" signal "L5VCC")
		(12 "In5.Cu" signal "L6")
		(14 "In6.Cu" signal "L7GND")
		(2 "B.Cu" signal "BOTTOM")
		(9 "F.Adhes" user "F.Adhesive")
		(11 "B.Adhes" user "B.Adhesive")
		(13 "F.Paste" user "Package Geometry/Pastemask Top")
		(15 "B.Paste" user "Package Geometry/Pastemask Bottom")
		(5 "F.SilkS" user "Ref Des/Silkscreen Top")
		(7 "B.SilkS" user "Ref Des/Silkscreen Bottom")
		(1 "F.Mask" user "Board Geometry/Soldermask Top")
		(3 "B.Mask" user "Board Geometry/Soldermask Bottom")
		(17 "Dwgs.User" user "User.Drawings")
		(19 "Cmts.User" user "User.Comments")
		(21 "Eco1.User" user "User.Eco1")
		(23 "Eco2.User" user "User.Eco2")
		(25 "Edge.Cuts" user "Board Geometry/Outline")
		(27 "Margin" user)
		(31 "F.CrtYd" user "Package Geometry/Place Bound Top")
		(29 "B.CrtYd" user "Package Geometry/Place Bound Bottom")
		(35 "F.Fab" user "Ref Des/Assembly Top")
		(33 "B.Fab" user "Ref Des/Assembly Bottom")
	)
	(footprint ""
		(layer "F.Cu")
		(at 222.499936 -7.999984)
		(property "Reference" ""
			(at 0 0 0)
			(layer "F.SilkS")
			(hide yes)
			(effects
				(font
					(size 1.27 1.27)
				)
			)
		)
		(property "Value" "*"
			(at 6.2484 0.3429 0)
			(unlocked yes)
			(layer "F.Fab")
			(hide yes)
			(effects
				(font
					(size 1.016 1.016)
					(thickness 0.1524)
				)
			)
		)
		(duplicate_pad_numbers_are_jumpers no)
		(fp_poly
			(pts
				(arc
					(start 5.0673 0)
					(mid -5.0673 0)
					(end 5.0673 0)
				)
			)
			(stroke
				(width 0)
				(type default)
			)
			(fill no)
			(layer "B.CrtYd")
		)
		(fp_poly
			(pts
				(arc
					(start 5.0673 0)
					(mid -5.0673 0)
					(end 5.0673 0)
				)
			)
			(stroke
				(width 0)
				(type default)
			)
			(fill no)
			(layer "F.CrtYd")
		)
		(fp_poly
			(pts
				(arc
					(start 5.0673 0)
					(mid -5.0673 0)
					(end 5.0673 0)
				)
			)
			(stroke
				(width 0)
				(type default)
			)
			(fill no)
			(layer "B.Fab")
		)
		(fp_poly
			(pts
				(arc
					(start 5.0673 0)
					(mid -5.0673 0)
					(end 5.0673 0)
				)
			)
			(stroke
				(width 0)
				(type default)
			)
			(fill no)
			(layer "F.Fab")
		)
		(pad "1" thru_hole circle
			(at 0 0)
			(size 9.525 9.525)
			(drill 4.0132)
			(layers "*.Cu" "*.Mask")
			(remove_unused_layers no)
			(net "Net_84")
			(clearance -2.2479)
			(thermal_gap 0.3048)
			(padstack
				(mode front_inner_back)
				(layer "Inner"
					(shape circle)
					(size 4.4196 4.4196)
					(clearance 0.3048)
				)
				(layer "B.Cu"
					(shape circle)
					(size 9.525 9.525)
					(clearance -2.2479)
				)
			)
		)
	)
	(footprint ""
		(layer "F.Cu")
		(at 20.773136 -170.1038)
		(property "Reference" "C230"
			(at 0 0 0)
			(layer "F.SilkS")
			(hide yes)
			(effects
				(font
					(size 1.27 1.27)
				)
			)
		)
		(property "Value" "SCD1U16V2KX-3GP"
			(at 1.1811 -2.7051 0)
			(unlocked yes)
			(layer "F.Fab")
			(hide yes)
			(effects
				(font
					(size 1.016 1.016)
					(thickness 0.1524)
				)
			)
		)
		(property "Device Type" "C402H22"
			(at 1.1811 -4.2291 0)
			(unlocked yes)
			(layer "F.Fab")
			(hide yes)
			(effects
				(font
					(size 1.016 1.016)
					(thickness 0.1524)
				)
			)
		)
		(duplicate_pad_numbers_are_jumpers no)
		(fp_rect
			(start -0.4318 0.9525)
			(end 0.4318 -0.9525)
			(stroke
				(width 0)
				(type default)
			)
			(fill no)
			(layer "F.CrtYd")
		)
		(fp_rect
			(start -0.4318 0.9525)
			(end 0.4318 -0.9525)
			(stroke
				(width 0)
				(type default)
			)
			(fill no)
			(layer "F.Fab")
		)
		(pad "1" smd custom
			(at 0 -0.4445)
			(size 0.1524 0.1524)
			(layers "F.Cu" "F.Mask" "F.Paste")
			(net "P1V8_STBY")
			(options
				(clearance outline)
				(anchor circle)
			)
			(primitives
				(gr_poly
					(pts
						(arc
							(start 0.3048 -0.2032)
							(mid 0.275042 -0.275042)
							(end 0.2032 -0.3048)
						)
						(arc
							(start -0.2032 -0.3048)
							(mid -0.275042 -0.275042)
							(end -0.3048 -0.2032)
						)
						(arc
							(start -0.3048 0.2032)
							(mid -0.275042 0.275042)
							(end -0.2032 0.3048)
						)
						(arc
							(start 0.2032 0.3048)
							(mid 0.275042 0.275042)
							(end 0.3048 0.2032)
						)
					)
					(width 0)
					(fill yes)
				)
			)
		)
		(pad "2" smd custom
			(at 0 0.4445)
			(size 0.1524 0.1524)
			(layers "F.Cu" "F.Mask" "F.Paste")
			(net "GND")
			(options
				(clearance outline)
				(anchor circle)
			)
			(primitives
				(gr_poly
					(pts
						(arc
							(start 0.3048 -0.2032)
							(mid 0.275042 -0.275042)
							(end 0.2032 -0.3048)
						)
						(arc
							(start -0.2032 -0.3048)
							(mid -0.275042 -0.275042)
							(end -0.3048 -0.2032)
						)
						(arc
							(start -0.3048 0.2032)
							(mid -0.275042 0.275042)
							(end -0.2032 0.3048)
						)
						(arc
							(start 0.2032 0.3048)
							(mid 0.275042 0.275042)
							(end 0.3048 0.2032)
						)
					)
					(width 0)
					(fill yes)
				)
			)
		)
	)
	(footprint ""
		(layer "F.Cu")
		(at 60.9092 -121.3612 90)
		(property "Reference" "U29"
			(at 0 0 90)
			(layer "F.SilkS")
			(hide yes)
			(effects
				(font
					(size 1.27 1.27)
				)
			)
		)
		(property "Value" "MX25L25635FMI-10G-GP"
			(at 0 -14.6812 90)
			(unlocked yes)
			(layer "F.Fab")
			(hide yes)
			(effects
				(font
					(size 1.016 1.016)
					(thickness 0.1524)
				)
			)
		)
		(property "Device Type" "SOIC16-6H105"
			(at 0 -16.2052 90)
			(unlocked yes)
			(layer "F.Fab")
			(hide yes)
			(effects
				(font
					(size 1.016 1.016)
					(thickness 0.1524)
				)
			)
		)
		(duplicate_pad_numbers_are_jumpers no)
		(fp_line
			(start 4.7498 -3.2258)
			(end 4.7498 3.2258)
			(stroke
				(width 0.1524)
				(type default)
			)
			(layer "F.SilkS")
		)
		(fp_line
			(start -5.588 -3.2258)
			(end 4.7498 -3.2258)
			(stroke
				(width 0.1524)
				(type default)
			)
			(layer "F.SilkS")
		)
		(fp_line
			(start -5.588 -0.50038)
			(end -5.08762 0)
			(stroke
				(width 0.1524)
				(type default)
			)
			(layer "F.SilkS")
		)
		(fp_line
			(start -5.08762 0)
			(end -5.588 0.50038)
			(stroke
				(width 0.1524)
				(type default)
			)
			(layer "F.SilkS")
		)
		(fp_line
			(start 4.7498 3.2258)
			(end -5.588 3.2258)
			(stroke
				(width 0.1524)
				(type default)
			)
			(layer "F.SilkS")
		)
		(fp_line
			(start -5.4102 3.2258)
			(end -5.4102 5.7912)
			(stroke
				(width 0.508)
				(type default)
			)
			(layer "F.SilkS")
		)
		(fp_line
			(start -5.588 3.2258)
			(end -5.588 -3.2258)
			(stroke
				(width 0.1524)
				(type default)
			)
			(layer "F.SilkS")
		)
		(fp_poly
			(pts
				(xy -4.764786 -3.2258) (xy 4.7625 -3.2258) (xy 4.7625 3.2258) (xy -4.764786 3.2258)
			)
			(stroke
				(width 0)
				(type default)
			)
			(fill yes)
			(layer "F.SilkS")
		)
		(fp_poly
			(pts
				(xy -5.6642 6.0452) (xy 5.6642 6.0452) (xy 5.6642 -6.0452) (xy -5.6642 -6.0452)
			)
			(stroke
				(width 0)
				(type default)
			)
			(fill no)
			(layer "F.CrtYd")
		)
		(fp_poly
			(pts
				(xy -5.6642 -6.0452) (xy 5.6642 -6.0452) (xy 5.6642 6.0452) (xy -5.6642 6.0452)
			)
			(stroke
				(width 0)
				(type default)
			)
			(fill no)
			(layer "F.Fab")
		)
		(pad "1" smd rect
			(at -4.445 4.71805 90)
			(size 0.635 1.651)
			(layers "F.Cu" "F.Mask" "F.Paste")
			(net "PU_IBMC_BT_HOLD_N")
		)
		(pad "2" smd rect
			(at -3.175 4.71805 90)
			(size 0.635 1.651)
			(layers "F.Cu" "F.Mask" "F.Paste")
			(net "P3V3_STBY")
		)
		(pad "3" smd rect
			(at -1.905 4.71805 90)
			(size 0.635 1.651)
			(layers "F.Cu" "F.Mask" "F.Paste")
			(net "FLA1_SPI_RST")
		)
		(pad "4" smd rect
			(at -0.635 4.71805 90)
			(size 0.635 1.651)
			(layers "F.Cu" "F.Mask" "F.Paste")
			(net "Net_541")
		)
		(pad "5" smd rect
			(at 0.635 4.71805 90)
			(size 0.635 1.651)
			(layers "F.Cu" "F.Mask" "F.Paste")
			(net "Net_540")
		)
		(pad "6" smd rect
			(at 1.905 4.71805 90)
			(size 0.635 1.651)
			(layers "F.Cu" "F.Mask" "F.Paste")
			(net "Net_539")
		)
		(pad "7" smd rect
			(at 3.175 4.71805 90)
			(size 0.635 1.651)
			(layers "F.Cu" "F.Mask" "F.Paste")
			(net "FLA_CS_1_R")
		)
		(pad "8" smd rect
			(at 4.445 4.71805 90)
			(size 0.635 1.651)
			(layers "F.Cu" "F.Mask" "F.Paste")
			(net "BMC_SPI_MISO_R")
		)
		(pad "9" smd rect
			(at 4.445 -4.71805 90)
			(size 0.635 1.651)
			(layers "F.Cu" "F.Mask" "F.Paste")
			(net "FLA1_WP_N")
		)
		(pad "10" smd rect
			(at 3.175 -4.71805 90)
			(size 0.635 1.651)
			(layers "F.Cu" "F.Mask" "F.Paste")
			(net "GND")
		)
		(pad "11" smd rect
			(at 1.905 -4.71805 90)
			(size 0.635 1.651)
			(layers "F.Cu" "F.Mask" "F.Paste")
			(net "Net_538")
		)
		(pad "12" smd rect
			(at 0.635 -4.71805 90)
			(size 0.635 1.651)
			(layers "F.Cu" "F.Mask" "F.Paste")
			(net "Net_537")
		)
		(pad "13" smd rect
			(at -0.635 -4.71805 90)
			(size 0.635 1.651)
			(layers "F.Cu" "F.Mask" "F.Paste")
			(net "Net_536")
		)
		(pad "14" smd rect
			(at -1.905 -4.71805 90)
			(size 0.635 1.651)
			(layers "F.Cu" "F.Mask" "F.Paste")
			(net "Net_535")
		)
		(pad "15" smd rect
			(at -3.175 -4.71805 90)
			(size 0.635 1.651)
			(layers "F.Cu" "F.Mask" "F.Paste")
			(net "BMC_SPI_MOSI_R")
		)
		(pad "16" smd rect
			(at -4.445 -4.71805 90)
			(size 0.635 1.651)
			(layers "F.Cu" "F.Mask" "F.Paste")
			(net "BMC_SPI_CLK_R")
		)
	)
	(footprint ""
		(layer "F.Cu")
		(at 65.641474 -179.457096)
		(property "Reference" "R81"
			(at 0 0 0)
			(layer "F.SilkS")
			(hide yes)
			(effects
				(font
					(size 1.27 1.27)
				)
			)
		)
		(property "Value" "4K75R2F-1-GP"
			(at 0.064008 -3.993896 0)
			(unlocked yes)
			(layer "F.Fab")
			(hide yes)
			(effects
				(font
					(size 1.016 1.016)
					(thickness 0.1524)
				)
			)
		)
		(property "Device Type" "R402H16"
			(at 0.064008 -5.517896 0)
			(unlocked yes)
			(layer "F.Fab")
			(hide yes)
			(effects
				(font
					(size 1.016 1.016)
					(thickness 0.1524)
				)
			)
		)
		(duplicate_pad_numbers_are_jumpers no)
		(fp_line
			(start -0.508 -0.9398)
			(end -0.508 0.9398)
			(stroke
				(width 0.1524)
				(type default)
			)
			(layer "F.SilkS")
		)
		(fp_line
			(start 0.508 -0.9398)
			(end -0.508 -0.9398)
			(stroke
				(width 0.1524)
				(type default)
			)
			(layer "F.SilkS")
		)
		(fp_rect
			(start -0.508 0.9398)
			(end 0.508 -0.9398)
			(stroke
				(width 0)
				(type default)
			)
			(fill no)
			(layer "F.CrtYd")
		)
		(fp_rect
			(start -0.508 0.9398)
			(end 0.508 -0.9398)
			(stroke
				(width 0)
				(type default)
			)
			(fill no)
			(layer "F.Fab")
		)
		(pad "1" smd custom
			(at 0 -0.4445)
			(size 0.1397 0.1397)
			(layers "F.Cu" "F.Mask" "F.Paste")
			(net "P3V3_STBY")
			(options
				(clearance outline)
				(anchor circle)
			)
			(primitives
				(gr_poly
					(pts
						(arc
							(start -0.1778 -0.2794)
							(mid -0.249642 -0.249642)
							(end -0.2794 -0.1778)
						)
						(arc
							(start -0.2794 0.1778)
							(mid -0.249642 0.249642)
							(end -0.1778 0.2794)
						)
						(arc
							(start 0.1778 0.2794)
							(mid 0.249642 0.249642)
							(end 0.2794 0.1778)
						)
						(arc
							(start 0.2794 -0.1778)
							(mid 0.249642 -0.249642)
							(end 0.1778 -0.2794)
						)
					)
					(width 0)
					(fill yes)
				)
			)
		)
		(pad "2" smd custom
			(at 0 0.4445)
			(size 0.1397 0.1397)
			(layers "F.Cu" "F.Mask" "F.Paste")
			(net "VREF_2V2")
			(options
				(clearance outline)
				(anchor circle)
			)
			(primitives
				(gr_poly
					(pts
						(arc
							(start -0.1778 -0.2794)
							(mid -0.249642 -0.249642)
							(end -0.2794 -0.1778)
						)
						(arc
							(start -0.2794 0.1778)
							(mid -0.249642 0.249642)
							(end -0.1778 0.2794)
						)
						(arc
							(start 0.1778 0.2794)
							(mid 0.249642 0.249642)
							(end 0.2794 0.1778)
						)
						(arc
							(start 0.2794 -0.1778)
							(mid 0.249642 -0.249642)
							(end 0.1778 -0.2794)
						)
					)
					(width 0)
					(fill yes)
				)
			)
		)
	)
	(footprint ""
		(layer "F.Cu")
		(at 75.69581 -150.579074 90)
		(property "Reference" "R307"
			(at 0 0 90)
			(layer "F.SilkS")
			(hide yes)
			(effects
				(font
					(size 1.27 1.27)
				)
			)
		)
		(property "Value" "10KR2F-2-GP"
			(at 0.064008 -3.993896 90)
			(unlocked yes)
			(layer "F.Fab")
			(hide yes)
			(effects
				(font
					(size 1.016 1.016)
					(thickness 0.1524)
				)
			)
		)
		(property "Device Type" "R402H16"
			(at 0.064008 -5.517896 90)
			(unlocked yes)
			(layer "F.Fab")
			(hide yes)
			(effects
				(font
					(size 1.016 1.016)
					(thickness 0.1524)
				)
			)
		)
		(duplicate_pad_numbers_are_jumpers no)
		(fp_line
			(start 0.508 -0.9398)
			(end -0.508 -0.9398)
			(stroke
				(width 0.1524)
				(type default)
			)
			(layer "F.SilkS")
		)
		(fp_line
			(start -0.508 -0.9398)
			(end -0.508 0.9398)
			(stroke
				(width 0.1524)
				(type default)
			)
			(layer "F.SilkS")
		)
		(fp_rect
			(start -0.508 0.9398)
			(end 0.508 -0.9398)
			(stroke
				(width 0)
				(type default)
			)
			(fill no)
			(layer "F.CrtYd")
		)
		(fp_rect
			(start -0.508 0.9398)
			(end 0.508 -0.9398)
			(stroke
				(width 0)
				(type default)
			)
			(fill no)
			(layer "F.Fab")
		)
		(pad "1" smd custom
			(at 0 -0.4445 90)
			(size 0.1397 0.1397)
			(layers "F.Cu" "F.Mask" "F.Paste")
			(net "P3V3_STBY")
			(options
				(clearance outline)
				(anchor circle)
			)
			(primitives
				(gr_poly
					(pts
						(arc
							(start -0.1778 -0.2794)
							(mid -0.249642 -0.249642)
							(end -0.2794 -0.1778)
						)
						(arc
							(start -0.2794 0.1778)
							(mid -0.249642 0.249642)
							(end -0.1778 0.2794)
						)
						(arc
							(start 0.1778 0.2794)
							(mid 0.249642 0.249642)
							(end 0.2794 0.1778)
						)
						(arc
							(start 0.2794 -0.1778)
							(mid 0.249642 -0.249642)
							(end 0.1778 -0.2794)
						)
					)
					(width 0)
					(fill yes)
				)
			)
		)
		(pad "2" smd custom
			(at 0 0.4445 90)
			(size 0.1397 0.1397)
			(layers "F.Cu" "F.Mask" "F.Paste")
			(net "50M_CLK_OE")
			(options
				(clearance outline)
				(anchor circle)
			)
			(primitives
				(gr_poly
					(pts
						(arc
							(start -0.1778 -0.2794)
							(mid -0.249642 -0.249642)
							(end -0.2794 -0.1778)
						)
						(arc
							(start -0.2794 0.1778)
							(mid -0.249642 0.249642)
							(end -0.1778 0.2794)
						)
						(arc
							(start 0.1778 0.2794)
							(mid 0.249642 0.249642)
							(end 0.2794 0.1778)
						)
						(arc
							(start 0.2794 -0.1778)
							(mid 0.249642 -0.249642)
							(end 0.1778 -0.2794)
						)
					)
					(width 0)
					(fill yes)
				)
			)
		)
	)
	(footprint ""
		(layer "F.Cu")
		(at 229.682548 -18.16481 -90)
		(property "Reference" "G1"
			(at 0 0 270)
			(layer "F.SilkS")
			(hide yes)
			(effects
				(font
					(size 1.27 1.27)
				)
			)
		)
		(property "Value" "GAP-CLOSE-PWR-4-GP"
			(at -2.4638 -0.5461 270)
			(unlocked yes)
			(layer "F.Fab")
			(hide yes)
			(effects
				(font
					(size 1.016 1.016)
					(thickness 0.1524)
				)
			)
		)
		(property "Device Type" "GAP-CLOSE-PWR-4"
			(at -2.4638 -2.0701 270)
			(unlocked yes)
			(layer "F.Fab")
			(hide yes)
			(effects
				(font
					(size 1.016 1.016)
					(thickness 0.1524)
				)
			)
		)
		(duplicate_pad_numbers_are_jumpers no)
		(fp_rect
			(start -0.2794 0.254)
			(end 0.2794 -0.254)
			(stroke
				(width 0)
				(type default)
			)
			(fill no)
			(layer "F.CrtYd")
		)
		(fp_rect
			(start -0.2794 0.254)
			(end 0.2794 -0.254)
			(stroke
				(width 0)
				(type default)
			)
			(fill no)
			(layer "F.Fab")
		)
		(pad "1" smd rect
			(at -0.0635 0 270)
			(size 0.1778 0.254)
			(layers "F.Cu" "F.Mask" "F.Paste")
			(net "P5V_STBY")
		)
		(pad "2" smd rect
			(at 0.0635 0 270)
			(size 0.1778 0.254)
			(layers "F.Cu" "F.Mask" "F.Paste")
			(net "P5V_CC")
		)
	)
	(footprint ""
		(layer "F.Cu")
		(at 181.1528 -99.695)
		(property "Reference" "R556"
			(at 0 0 0)
			(layer "F.SilkS")
			(hide yes)
			(effects
				(font
					(size 1.27 1.27)
				)
			)
		)
		(property "Value" "0R2J-2-GP"
			(at 0.064008 -3.993896 0)
			(unlocked yes)
			(layer "F.Fab")
			(hide yes)
			(effects
				(font
					(size 1.016 1.016)
					(thickness 0.1524)
				)
			)
		)
		(property "Device Type" "R402H16"
			(at 0.064008 -5.517896 0)
			(unlocked yes)
			(layer "F.Fab")
			(hide yes)
			(effects
				(font
					(size 1.016 1.016)
					(thickness 0.1524)
				)
			)
		)
		(duplicate_pad_numbers_are_jumpers no)
		(fp_line
			(start -0.508 -0.9398)
			(end -0.508 0.9398)
			(stroke
				(width 0.1524)
				(type default)
			)
			(layer "F.SilkS")
		)
		(fp_line
			(start 0.508 -0.9398)
			(end -0.508 -0.9398)
			(stroke
				(width 0.1524)
				(type default)
			)
			(layer "F.SilkS")
		)
		(fp_rect
			(start -0.508 0.9398)
			(end 0.508 -0.9398)
			(stroke
				(width 0)
				(type default)
			)
			(fill no)
			(layer "F.CrtYd")
		)
		(fp_rect
			(start -0.508 0.9398)
			(end 0.508 -0.9398)
			(stroke
				(width 0)
				(type default)
			)
			(fill no)
			(layer "F.Fab")
		)
		(pad "1" smd custom
			(at 0 -0.4445)
			(size 0.1397 0.1397)
			(layers "F.Cu" "F.Mask" "F.Paste")
			(net "TEMP_1_SDA")
			(options
				(clearance outline)
				(anchor circle)
			)
			(primitives
				(gr_poly
					(pts
						(arc
							(start -0.1778 -0.2794)
							(mid -0.249642 -0.249642)
							(end -0.2794 -0.1778)
						)
						(arc
							(start -0.2794 0.1778)
							(mid -0.249642 0.249642)
							(end -0.1778 0.2794)
						)
						(arc
							(start 0.1778 0.2794)
							(mid 0.249642 0.249642)
							(end 0.2794 0.1778)
						)
						(arc
							(start 0.2794 -0.1778)
							(mid 0.249642 -0.249642)
							(end 0.1778 -0.2794)
						)
					)
					(width 0)
					(fill yes)
				)
			)
		)
		(pad "2" smd custom
			(at 0 0.4445)
			(size 0.1397 0.1397)
			(layers "F.Cu" "F.Mask" "F.Paste")
			(net "I2C_IOM_SDA")
			(options
				(clearance outline)
				(anchor circle)
			)
			(primitives
				(gr_poly
					(pts
						(arc
							(start -0.1778 -0.2794)
							(mid -0.249642 -0.249642)
							(end -0.2794 -0.1778)
						)
						(arc
							(start -0.2794 0.1778)
							(mid -0.249642 0.249642)
							(end -0.1778 0.2794)
						)
						(arc
							(start 0.1778 0.2794)
							(mid 0.249642 0.249642)
							(end 0.2794 0.1778)
						)
						(arc
							(start 0.2794 -0.1778)
							(mid 0.249642 -0.249642)
							(end 0.1778 -0.2794)
						)
					)
					(width 0)
					(fill yes)
				)
			)
		)
	)
)
